# TIMECARD (Time Appliance Project (Time Card)) — schematic netlist excerpt (pin names and nets, part order shuffled) for the footprints in the layout excerpt that follows; sources: Cadence DE-HDL packaged netlist, KiCad conversion of R4006-B0001-02_R01.brd

R294  RESISTOR  33OHM 1%  pkg SMC_0402R_H016  page 32 : \1\ = XP5R0V_PG ; \2\ = FPGA_CFG_INIT_N
R375  RESISTOR  100OHM 1%  pkg SMC_0402R_H016  page 26 : \1\ = FPGA_OUT_SMA3_LED_GREEN_N ; \2\ = UNNAMED_14_LED4PV14_I267_4
SP30  SOLDER_PREFORM  pkg 0201_SOLDER_PREFORM_4MIL  page 34 : \1\ = NC ; \2\ = NC

(kicad_pcb
	(version 20260206)
	(generator "pcbnew")
	(generator_version "10.0")
	(general
		(thickness 1.6)
		(legacy_teardrops no)
	)
	(paper "A4")
	(title_block
		(title "timecard-production-celestica-r4006 — R4006-B0001-02_R01.brd")
		(comment 1 "Time Appliance Project (Time Card) / footprints 25-27 of 1113")
	)
	(layers
		(0 "F.Cu" signal "TOP")
		(4 "In1.Cu" signal "L02_GND1")
		(6 "In2.Cu" signal "L03_SIG1")
		(8 "In3.Cu" signal "L04_GND2")
		(10 "In4.Cu" signal "L05_VCC1")
		(12 "In5.Cu" signal "L06_VCC2")
		(14 "In6.Cu" signal "L07_GND3")
		(16 "In7.Cu" signal "L08_SIG2")
		(18 "In8.Cu" signal "L09_GND4")
		(2 "B.Cu" signal "BOTTOM")
		(9 "F.Adhes" user "F.Adhesive")
		(11 "B.Adhes" user "B.Adhesive")
		(13 "F.Paste" user "Package Geometry/Pastemask Top")
		(15 "B.Paste" user "Package Geometry/Pastemask Bottom")
		(5 "F.SilkS" user "Ref Des/Silkscreen Top")
		(7 "B.SilkS" user "Ref Des/Silkscreen Bottom")
		(1 "F.Mask" user "Board Geometry/Soldermask Top")
		(3 "B.Mask" user "Board Geometry/Soldermask Bottom")
		(17 "Dwgs.User" user "User.Drawings")
		(19 "Cmts.User" user "User.Comments")
		(21 "Eco1.User" user "User.Eco1")
		(23 "Eco2.User" user "User.Eco2")
		(25 "Edge.Cuts" user "Board Geometry/Outline")
		(27 "Margin" user)
		(31 "F.CrtYd" user "Package Geometry/Place Bound Top")
		(29 "B.CrtYd" user "Package Geometry/Place Bound Bottom")
		(35 "F.Fab" user "Ref Des/Assembly Top")
		(33 "B.Fab" user "Ref Des/Assembly Bottom")
	)
	(footprint ""
		(layer "F.Cu")
		(at 10.7188 -68.201032 90)
		(property "Reference" "R375"
			(at 3.426968 -0.39243 90)
			(unlocked yes)
			(layer "F.SilkS")
			(effects
				(font
					(size 0.7874 0.5842)
					(thickness 0.1524)
				)
			)
		)
		(property "Value" "VAL*"
			(at 0.02032 2.13233 90)
			(unlocked yes)
			(layer "F.Fab")
			(hide yes)
			(effects
				(font
					(size 0.7874 0.5842)
					(thickness 0.1524)
				)
			)
		)
		(property "Device Type" "RESISTOR-G155-11000-01,100OHM,A"
			(at 0.008382 1.210564 90)
			(unlocked yes)
			(layer "F.Fab")
			(hide yes)
			(effects
				(font
					(size 0.7874 0.5842)
					(thickness 0.1524)
				)
			)
		)
		(property "User Part Number" "PARTNUM*"
			(at 0.02032 4.024884 90)
			(unlocked yes)
			(layer "Cmts.User")
			(hide yes)
			(effects
				(font
					(size 0.7874 0.5842)
					(thickness 0.1524)
				)
			)
		)
		(property "Tolerance" "TOL*"
			(at 0.044704 3.05435 90)
			(unlocked yes)
			(layer "Cmts.User")
			(hide yes)
			(effects
				(font
					(size 0.7874 0.5842)
					(thickness 0.1524)
				)
			)
		)
		(duplicate_pad_numbers_are_jumpers no)
		(fp_line
			(start 1.143 -0.5588)
			(end -1.143 -0.5588)
			(stroke
				(width 0.1)
				(type default)
			)
			(layer "F.SilkS")
		)
		(fp_line
			(start -1.143 -0.5588)
			(end -1.143 0.5588)
			(stroke
				(width 0.1)
				(type default)
			)
			(layer "F.SilkS")
		)
		(fp_line
			(start 1.143 0.5588)
			(end 1.143 -0.5588)
			(stroke
				(width 0.1)
				(type default)
			)
			(layer "F.SilkS")
		)
		(fp_line
			(start -1.143 0.5588)
			(end 1.143 0.5588)
			(stroke
				(width 0.1)
				(type default)
			)
			(layer "F.SilkS")
		)
		(fp_poly
			(pts
				(xy -1.143 0.5588) (xy 1.143 0.5588) (xy 1.143 -0.5588) (xy -1.143 -0.5588)
			)
			(stroke
				(width 0)
				(type default)
			)
			(fill no)
			(layer "F.CrtYd")
		)
		(fp_line
			(start 0.508 -0.3048)
			(end -0.508 -0.3048)
			(stroke
				(width 0.1)
				(type default)
			)
			(layer "F.Fab")
		)
		(fp_line
			(start -0.508 -0.3048)
			(end -0.508 0.3048)
			(stroke
				(width 0.1)
				(type default)
			)
			(layer "F.Fab")
		)
		(fp_line
			(start 0.508 0.3048)
			(end 0.508 -0.3048)
			(stroke
				(width 0.1)
				(type default)
			)
			(layer "F.Fab")
		)
		(fp_line
			(start -0.508 0.3048)
			(end 0.508 0.3048)
			(stroke
				(width 0.1)
				(type default)
			)
			(layer "F.Fab")
		)
		(pad "1" smd rect
			(at -0.5334 0 90)
			(size 0.7112 0.6096)
			(layers "F.Cu" "F.Mask" "F.Paste")
			(net "FPGA_OUT_SMA3_LED_GREEN_N")
		)
		(pad "2" smd rect
			(at 0.5334 0 90)
			(size 0.7112 0.6096)
			(layers "F.Cu" "F.Mask" "F.Paste")
			(net "UNNAMED_14_LED4PV14_I267_4")
		)
		(zone
			(layer "F.Cu")
			(hatch none 0.5)
			(connect_pads
				(clearance 0)
			)
			(min_thickness 0.25)
			(keepout
				(tracks allowed)
				(vias not_allowed)
				(pads allowed)
				(copperpour not_allowed)
				(footprints allowed)
			)
			(placement
				(enabled no)
				(sheetname "")
			)
			(fill
				(thermal_gap 0.5)
				(thermal_bridge_width 0.5)
				(island_removal_mode 0)
			)
			(polygon
				(pts
					(xy 11.0236 -68.124832) (xy 11.0236 -68.277232) (xy 10.414 -68.277232) (xy 10.414 -68.124832)
				)
			)
		)
		(zone
			(layer "F.Cu")
			(hatch none 0.5)
			(connect_pads
				(clearance 0)
			)
			(min_thickness 0.25)
			(keepout
				(tracks not_allowed)
				(vias allowed)
				(pads allowed)
				(copperpour not_allowed)
				(footprints allowed)
			)
			(placement
				(enabled no)
				(sheetname "")
			)
			(fill
				(thermal_gap 0.5)
				(thermal_bridge_width 0.5)
				(island_removal_mode 0)
			)
			(polygon
				(pts
					(xy 11.0236 -68.124832) (xy 11.0236 -68.277232) (xy 10.414 -68.277232) (xy 10.414 -68.124832)
				)
			)
		)
	)
	(footprint ""
		(layer "F.Cu")
		(at 64.897 -120.269)
		(property "Reference" "SP30"
			(at 0 0 0)
			(layer "F.SilkS")
			(hide yes)
			(effects
				(font
					(size 1.27 1.27)
				)
			)
		)
		(property "Value" ""
			(at 0 0 0)
			(layer "F.Fab")
			(effects
				(font
					(size 1.27 1.27)
				)
			)
		)
		(duplicate_pad_numbers_are_jumpers no)
	)
	(footprint ""
		(layer "F.Cu")
		(at 36.7284 -97.8154 180)
		(property "Reference" "R294"
			(at -2.43586 -5.93725 0)
			(unlocked yes)
			(layer "F.SilkS")
			(effects
				(font
					(size 0.7874 0.5842)
					(thickness 0.1524)
				)
			)
		)
		(property "Value" "VAL*"
			(at 0.02032 2.13233 180)
			(unlocked yes)
			(layer "F.Fab")
			(hide yes)
			(effects
				(font
					(size 0.7874 0.5842)
					(thickness 0.1524)
				)
			)
		)
		(property "Device Type" "RESISTOR-G155-133R0-01,33OHM,1%"
			(at 0.008382 1.210564 180)
			(unlocked yes)
			(layer "F.Fab")
			(hide yes)
			(effects
				(font
					(size 0.7874 0.5842)
					(thickness 0.1524)
				)
			)
		)
		(property "User Part Number" "PARTNUM*"
			(at 0.02032 4.024884 180)
			(unlocked yes)
			(layer "Cmts.User")
			(hide yes)
			(effects
				(font
					(size 0.7874 0.5842)
					(thickness 0.1524)
				)
			)
		)
		(property "Tolerance" "TOL*"
			(at 0.044704 3.05435 180)
			(unlocked yes)
			(layer "Cmts.User")
			(hide yes)
			(effects
				(font
					(size 0.7874 0.5842)
					(thickness 0.1524)
				)
			)
		)
		(duplicate_pad_numbers_are_jumpers no)
		(fp_line
			(start 1.143 0.5588)
			(end 1.143 -0.5588)
			(stroke
				(width 0.1)
				(type default)
			)
			(layer "F.SilkS")
		)
		(fp_line
			(start 1.143 -0.5588)
			(end -1.143 -0.5588)
			(stroke
				(width 0.1)
				(type default)
			)
			(layer "F.SilkS")
		)
		(fp_line
			(start -1.143 0.5588)
			(end 1.143 0.5588)
			(stroke
				(width 0.1)
				(type default)
			)
			(layer "F.SilkS")
		)
		(fp_line
			(start -1.143 -0.5588)
			(end -1.143 0.5588)
			(stroke
				(width 0.1)
				(type default)
			)
			(layer "F.SilkS")
		)
		(fp_rect
			(start -1.143 0.5588)
			(end 1.143 -0.5588)
			(stroke
				(width 0)
				(type default)
			)
			(fill no)
			(layer "F.CrtYd")
		)
		(fp_line
			(start 0.508 0.3048)
			(end 0.508 -0.3048)
			(stroke
				(width 0.1)
				(type default)
			)
			(layer "F.Fab")
		)
		(fp_line
			(start 0.508 -0.3048)
			(end -0.508 -0.3048)
			(stroke
				(width 0.1)
				(type default)
			)
			(layer "F.Fab")
		)
		(fp_line
			(start -0.508 0.3048)
			(end 0.508 0.3048)
			(stroke
				(width 0.1)
				(type default)
			)
			(layer "F.Fab")
		)
		(fp_line
			(start -0.508 -0.3048)
			(end -0.508 0.3048)
			(stroke
				(width 0.1)
				(type default)
			)
			(layer "F.Fab")
		)
		(pad "1" smd rect
			(at -0.5334 0 180)
			(size 0.7112 0.6096)
			(layers "F.Cu" "F.Mask" "F.Paste")
			(net "XP5R0V_PG")
		)
		(pad "2" smd rect
			(at 0.5334 0 180)
			(size 0.7112 0.6096)
			(layers "F.Cu" "F.Mask" "F.Paste")
			(net "FPGA_CFG_INIT_N")
		)
		(zone
			(layer "F.Cu")
			(hatch none 0.5)
			(connect_pads
				(clearance 0)
			)
			(min_thickness 0.25)
			(keepout
				(tracks allowed)
				(vias not_allowed)
				(pads allowed)
				(copperpour not_allowed)
				(footprints allowed)
			)
			(placement
				(enabled no)
				(sheetname "")
			)
			(fill
				(thermal_gap 0.5)
				(thermal_bridge_width 0.5)
				(island_removal_mode 0)
			)
			(polygon
				(pts
					(xy 36.8046 -98.1202) (xy 36.6522 -98.1202) (xy 36.6522 -97.5106) (xy 36.8046 -97.5106)
				)
			)
		)
	)
)
